# TIMECARD (Time Appliance Project (Time Card)) — schematic netlist excerpt (pin names and nets, part order shuffled) for the footprints in the layout excerpt that follows; sources: Cadence DE-HDL packaged netlist, KiCad conversion of R4006-B0001-02_R01.brd

TP31  TP_PIONT  pkg TP010CT020B030_PTH  page 25 : \1\ = SMA4_SIG_IN_BF_EN_N
C16  CAPACITOR  100PF 50V 10%  pkg SMC_0201R  page 28 : \1\ = UNNAMED_517_CAPACITOR_I30_1 ; \2\ = XP3R3V_FB_R_TO_AGND

(kicad_pcb
	(version 20260206)
	(generator "pcbnew")
	(generator_version "10.0")
	(general
		(thickness 1.6)
		(legacy_teardrops no)
	)
	(paper "A4")
	(title_block
		(title "timecard-production-celestica-r4006 — R4006-B0001-02_R01.brd")
		(comment 1 "Time Appliance Project (Time Card) / footprints 307-308 of 1113")
	)
	(layers
		(0 "F.Cu" signal "TOP")
		(4 "In1.Cu" signal "L02_GND1")
		(6 "In2.Cu" signal "L03_SIG1")
		(8 "In3.Cu" signal "L04_GND2")
		(10 "In4.Cu" signal "L05_VCC1")
		(12 "In5.Cu" signal "L06_VCC2")
		(14 "In6.Cu" signal "L07_GND3")
		(16 "In7.Cu" signal "L08_SIG2")
		(18 "In8.Cu" signal "L09_GND4")
		(2 "B.Cu" signal "BOTTOM")
		(9 "F.Adhes" user "F.Adhesive")
		(11 "B.Adhes" user "B.Adhesive")
		(13 "F.Paste" user "Package Geometry/Pastemask Top")
		(15 "B.Paste" user "Package Geometry/Pastemask Bottom")
		(5 "F.SilkS" user "Ref Des/Silkscreen Top")
		(7 "B.SilkS" user "Ref Des/Silkscreen Bottom")
		(1 "F.Mask" user "Board Geometry/Soldermask Top")
		(3 "B.Mask" user "Board Geometry/Soldermask Bottom")
		(17 "Dwgs.User" user "User.Drawings")
		(19 "Cmts.User" user "User.Comments")
		(21 "Eco1.User" user "User.Eco1")
		(23 "Eco2.User" user "User.Eco2")
		(25 "Edge.Cuts" user "Board Geometry/Outline")
		(27 "Margin" user)
		(31 "F.CrtYd" user "Package Geometry/Place Bound Top")
		(29 "B.CrtYd" user "Package Geometry/Place Bound Bottom")
		(35 "F.Fab" user "Ref Des/Assembly Top")
		(33 "B.Fab" user "Ref Des/Assembly Bottom")
	)
	(footprint ""
		(layer "F.Cu")
		(at 89.8652 -98.8568 180)
		(property "Reference" "C16"
			(at -1.905 -2.83337 0)
			(unlocked yes)
			(layer "F.SilkS")
			(effects
				(font
					(size 0.7874 0.5842)
					(thickness 0.1524)
				)
			)
		)
		(property "Value" "VAL*"
			(at 0.193548 2.13614 180)
			(unlocked yes)
			(layer "F.Fab")
			(hide yes)
			(effects
				(font
					(size 0.7874 0.5842)
					(thickness 0.1524)
				)
			)
		)
		(property "User Part Number" "PARTNUM*"
			(at 0.216154 4.185666 180)
			(unlocked yes)
			(layer "Cmts.User")
			(hide yes)
			(effects
				(font
					(size 0.7874 0.5842)
					(thickness 0.1524)
				)
			)
		)
		(property "Device Type" "CAPACITOR-G104-0B101-FK,100PF,A"
			(at 0.184404 1.180592 180)
			(unlocked yes)
			(layer "F.Fab")
			(hide yes)
			(effects
				(font
					(size 0.7874 0.5842)
					(thickness 0.1524)
				)
			)
		)
		(property "Tolerance" "TOL*"
			(at 0.216154 3.1496 180)
			(unlocked yes)
			(layer "Cmts.User")
			(hide yes)
			(effects
				(font
					(size 0.7874 0.5842)
					(thickness 0.1524)
				)
			)
		)
		(duplicate_pad_numbers_are_jumpers no)
		(fp_line
			(start 0.671322 0.4445)
			(end -0.671322 0.4445)
			(stroke
				(width 0.1)
				(type default)
			)
			(layer "F.SilkS")
		)
		(fp_line
			(start 0.671322 -0.4445)
			(end 0.671322 0.4445)
			(stroke
				(width 0.1)
				(type default)
			)
			(layer "F.SilkS")
		)
		(fp_line
			(start -0.671322 0.4445)
			(end -0.671322 -0.4445)
			(stroke
				(width 0.1)
				(type default)
			)
			(layer "F.SilkS")
		)
		(fp_line
			(start -0.671322 -0.4445)
			(end 0.671322 -0.4445)
			(stroke
				(width 0.1)
				(type default)
			)
			(layer "F.SilkS")
		)
		(fp_rect
			(start 0.671322 -0.4445)
			(end -0.671322 0.4445)
			(stroke
				(width 0)
				(type default)
			)
			(fill no)
			(layer "F.CrtYd")
		)
		(fp_line
			(start 0.31496 0.1651)
			(end 0.31496 -0.1651)
			(stroke
				(width 0.1)
				(type default)
			)
			(layer "F.Fab")
		)
		(fp_line
			(start 0.31496 -0.1651)
			(end -0.31496 -0.1651)
			(stroke
				(width 0.1)
				(type default)
			)
			(layer "F.Fab")
		)
		(fp_line
			(start -0.31496 0.1651)
			(end 0.31496 0.1651)
			(stroke
				(width 0.1)
				(type default)
			)
			(layer "F.Fab")
		)
		(fp_line
			(start -0.31496 -0.1651)
			(end -0.31496 0.1651)
			(stroke
				(width 0.1)
				(type default)
			)
			(layer "F.Fab")
		)
		(pad "1" smd rect
			(at -0.264922 0 180)
			(size 0.3048 0.381)
			(layers "F.Cu" "F.Mask" "F.Paste")
			(net "UNNAMED_517_CAPACITOR_I30_1")
		)
		(pad "2" smd rect
			(at 0.264922 0 180)
			(size 0.3048 0.381)
			(layers "F.Cu" "F.Mask" "F.Paste")
			(net "XP3R3V_FB_R_TO_AGND")
		)
		(zone
			(layer "F.Cu")
			(hatch none 0.5)
			(connect_pads
				(clearance 0)
			)
			(min_thickness 0.25)
			(keepout
				(tracks allowed)
				(vias not_allowed)
				(pads allowed)
				(copperpour not_allowed)
				(footprints allowed)
			)
			(placement
				(enabled no)
				(sheetname "")
			)
			(fill
				(thermal_gap 0.5)
				(thermal_bridge_width 0.5)
				(island_removal_mode 0)
			)
			(polygon
				(pts
					(xy 89.752678 -98.6663) (xy 89.977722 -98.6663) (xy 89.977722 -99.0473) (xy 89.752678 -99.0473)
				)
			)
		)
	)
	(footprint ""
		(layer "F.Cu")
		(at 16.3576 -17.78)
		(property "Reference" "TP31"
			(at 0.38735 3.6322 90)
			(unlocked yes)
			(layer "F.SilkS")
			(effects
				(font
					(size 0.635 0.4064)
					(thickness 0.1524)
				)
				(justify left)
			)
		)
		(property "Value" ""
			(at 0 0 0)
			(layer "F.Fab")
			(effects
				(font
					(size 1.27 1.27)
				)
			)
		)
		(property "Device Type" "TP_PIONT-TP010CT020B030_PTH-TPA"
			(at -1.341882 0.996696 0)
			(unlocked yes)
			(layer "F.Fab")
			(hide yes)
			(effects
				(font
					(size 0.7874 0.5842)
					(thickness 0.000001)
				)
				(justify left)
			)
		)
		(duplicate_pad_numbers_are_jumpers no)
		(fp_poly
			(pts
				(arc
					(start 0.889 0)
					(mid -0.889 0)
					(end 0.889 0)
				)
			)
			(stroke
				(width 0)
				(type default)
			)
			(fill no)
			(layer "B.CrtYd")
		)
		(fp_poly
			(pts
				(arc
					(start 0.889 0)
					(mid -0.889 0)
					(end 0.889 0)
				)
			)
			(stroke
				(width 0)
				(type default)
			)
			(fill no)
			(layer "F.CrtYd")
		)
		(pad "1" thru_hole circle
			(at 0 0)
			(size 0.508 0.508)
			(drill 0.254)
			(layers "*.Cu" "*.Mask")
			(remove_unused_layers no)
			(net "SMA4_SIG_IN_BF_EN_N")
			(clearance 0.1016)
			(padstack
				(mode front_inner_back)
				(layer "Inner"
					(shape circle)
					(size 0.508 0.508)
					(clearance 0.1016)
				)
				(layer "B.Cu"
					(shape circle)
					(size 0.762 0.762)
					(clearance -0.0254)
				)
			)
		)
	)
)
